# BASEBOARD_FAB2 (Tioga Pass) — schematic netlist excerpt (pin names and nets, part order shuffled) for the footprints in the layout excerpt that follows; sources: Cadence DE-HDL packaged netlist, KiCad conversion of Wiwynn_Tioga_Pass_MB.brd

C2U22  CAP_A  0.1UF 16V 10% X7R  pkg 0402V  page 108 : A = P3V3_STBY ; B = GND
C3M31  CAP_A  1.0UF 6.3V 10% X6S  pkg 0402V  page 127 : A = P1V05_PCH_STBY ; B = GND
C3N15  CAP_A  1.0UF 6.3V 10% X6S  pkg 0402V  page 132 : A = PVNN_PCH_STBY ; B = GND

(kicad_pcb
	(version 20260206)
	(generator "pcbnew")
	(generator_version "10.0")
	(general
		(thickness 1.6)
		(legacy_teardrops no)
	)
	(paper "A4")
	(title_block
		(title "Wiwynn_Tioga_Pass_MB.brd")
		(comment 1 "Tioga Pass / footprints 2848-2850 of 4770")
	)
	(layers
		(0 "F.Cu" signal "TOP")
		(4 "In1.Cu" signal "L2GND")
		(6 "In2.Cu" signal "L3")
		(8 "In3.Cu" signal "L4GND")
		(10 "In4.Cu" signal "L5")
		(12 "In5.Cu" signal "L6GND")
		(14 "In6.Cu" signal "L7VCC")
		(16 "In7.Cu" signal "L8VCC")
		(18 "In8.Cu" signal "L9GND")
		(20 "In9.Cu" signal "L10")
		(22 "In10.Cu" signal "L11GND")
		(24 "In11.Cu" signal "L12")
		(26 "In12.Cu" signal "L13GND")
		(2 "B.Cu" signal "BOTTOM")
		(9 "F.Adhes" user "F.Adhesive")
		(11 "B.Adhes" user "B.Adhesive")
		(13 "F.Paste" user "Package Geometry/Pastemask Top")
		(15 "B.Paste" user "Package Geometry/Pastemask Bottom")
		(5 "F.SilkS" user "Ref Des/Silkscreen Top")
		(7 "B.SilkS" user "Ref Des/Silkscreen Bottom")
		(1 "F.Mask" user "Board Geometry/Soldermask Top")
		(3 "B.Mask" user "Board Geometry/Soldermask Bottom")
		(17 "Dwgs.User" user "User.Drawings")
		(19 "Cmts.User" user "User.Comments")
		(21 "Eco1.User" user "User.Eco1")
		(23 "Eco2.User" user "User.Eco2")
		(25 "Edge.Cuts" user "Board Geometry/Outline")
		(27 "Margin" user)
		(31 "F.CrtYd" user "Package Geometry/Place Bound Top")
		(29 "B.CrtYd" user "Package Geometry/Place Bound Bottom")
		(35 "F.Fab" user "Ref Des/Assembly Top")
		(33 "B.Fab" user "Ref Des/Assembly Bottom")
	)
	(footprint ""
		(layer "B.Cu")
		(at 464.625944 -7.48792 180)
		(property "Reference" "C2U22"
			(at 0 0 0)
			(layer "B.SilkS")
			(hide yes)
			(effects
				(font
					(size 1.27 1.27)
				)
				(justify mirror)
			)
		)
		(property "Value" ""
			(at 0 0 0)
			(layer "B.Fab")
			(effects
				(font
					(size 1.27 1.27)
				)
				(justify mirror)
			)
		)
		(duplicate_pad_numbers_are_jumpers no)
		(fp_poly
			(pts
				(xy -0.3048 -0.1016) (xy -0.3048 0.9906) (xy 0.3048 0.9906) (xy 0.3048 -0.1016)
			)
			(stroke
				(width 0)
				(type default)
			)
			(fill no)
			(layer "B.CrtYd")
		)
		(fp_line
			(start 0.3048 0.9906)
			(end -0.3048 0.9906)
			(stroke
				(width 0.1)
				(type default)
			)
			(layer "B.Fab")
		)
		(fp_line
			(start 0.3048 -0.1016)
			(end 0.3048 0.9906)
			(stroke
				(width 0.1)
				(type default)
			)
			(layer "B.Fab")
		)
		(fp_line
			(start -0.3048 0.9906)
			(end -0.3048 -0.1016)
			(stroke
				(width 0.1)
				(type default)
			)
			(layer "B.Fab")
		)
		(fp_line
			(start -0.3048 -0.1016)
			(end 0.3048 -0.1016)
			(stroke
				(width 0.1)
				(type default)
			)
			(layer "B.Fab")
		)
		(pad "1" smd rect
			(at 0 0)
			(size 0.508 0.508)
			(layers "B.Cu" "B.Mask" "B.Paste")
			(net "P3V3_STBY")
		)
		(pad "2" smd rect
			(at 0 0.889)
			(size 0.508 0.508)
			(layers "B.Cu" "B.Mask" "B.Paste")
			(net "GND")
		)
		(zone
			(layer "B.Cu")
			(hatch none 0.5)
			(connect_pads
				(clearance 0)
			)
			(min_thickness 0.25)
			(keepout
				(tracks not_allowed)
				(vias allowed)
				(pads allowed)
				(copperpour not_allowed)
				(footprints allowed)
			)
			(placement
				(enabled no)
				(sheetname "")
			)
			(fill
				(thermal_gap 0.5)
				(thermal_bridge_width 0.5)
				(island_removal_mode 0)
			)
			(polygon
				(pts
					(xy 464.371944 -8.12292) (xy 464.879944 -8.12292) (xy 464.879944 -7.74192) (xy 464.371944 -7.74192)
				)
			)
		)
		(zone
			(layer "B.Cu")
			(hatch none 0.5)
			(connect_pads
				(clearance 0)
			)
			(min_thickness 0.25)
			(keepout
				(tracks allowed)
				(vias not_allowed)
				(pads allowed)
				(copperpour not_allowed)
				(footprints allowed)
			)
			(placement
				(enabled no)
				(sheetname "")
			)
			(fill
				(thermal_gap 0.5)
				(thermal_bridge_width 0.5)
				(island_removal_mode 0)
			)
			(polygon
				(pts
					(xy 464.371944 -7.74192) (xy 464.879944 -7.74192) (xy 464.879944 -8.12292) (xy 464.371944 -8.12292)
				)
			)
		)
	)
	(footprint ""
		(layer "B.Cu")
		(at 385.33705 -108.65485 90)
		(property "Reference" "C3N15"
			(at 0 0 90)
			(layer "B.SilkS")
			(hide yes)
			(effects
				(font
					(size 1.27 1.27)
				)
				(justify mirror)
			)
		)
		(property "Value" ""
			(at 0 0 90)
			(layer "B.Fab")
			(effects
				(font
					(size 1.27 1.27)
				)
				(justify mirror)
			)
		)
		(duplicate_pad_numbers_are_jumpers no)
		(fp_rect
			(start 0.2794 0.9144)
			(end -0.2794 -0.1143)
			(stroke
				(width 0)
				(type default)
			)
			(fill no)
			(layer "B.CrtYd")
		)
		(fp_line
			(start 0.2794 -0.1143)
			(end -0.2794 -0.1143)
			(stroke
				(width 0.1)
				(type default)
			)
			(layer "B.Fab")
		)
		(fp_line
			(start -0.2794 -0.1143)
			(end -0.2794 0.9144)
			(stroke
				(width 0.1)
				(type default)
			)
			(layer "B.Fab")
		)
		(fp_line
			(start 0.2794 0.9144)
			(end 0.2794 -0.1143)
			(stroke
				(width 0.1)
				(type default)
			)
			(layer "B.Fab")
		)
		(fp_line
			(start -0.2794 0.9144)
			(end 0.2794 0.9144)
			(stroke
				(width 0.1)
				(type default)
			)
			(layer "B.Fab")
		)
		(pad "1" smd custom
			(at 0 0)
			(size 0.10414 0.10414)
			(layers "B.Cu" "B.Mask" "B.Paste")
			(net "PVNN_PCH_STBY")
			(options
				(clearance outline)
				(anchor circle)
			)
			(primitives
				(gr_poly
					(pts
						(xy -0.20828 -0.08636) (xy -0.20828 0.08636) (xy -0.08636 0.20828) (xy 0.086614 0.20828) (xy 0.20828 0.086614)
						(xy 0.20828 -0.08636) (xy 0.08636 -0.20828) (xy -0.08636 -0.20828)
					)
					(width 0)
					(fill yes)
				)
			)
		)
		(pad "2" smd custom
			(at 0 0.8001)
			(size 0.10414 0.10414)
			(layers "B.Cu" "B.Mask" "B.Paste")
			(net "GND")
			(options
				(clearance outline)
				(anchor circle)
			)
			(primitives
				(gr_poly
					(pts
						(xy -0.20828 -0.08636) (xy -0.20828 0.08636) (xy -0.08636 0.20828) (xy 0.086614 0.20828) (xy 0.20828 0.086614)
						(xy 0.20828 -0.08636) (xy 0.08636 -0.20828) (xy -0.08636 -0.20828)
					)
					(width 0)
					(fill yes)
				)
			)
		)
		(zone
			(layer "B.Cu")
			(hatch none 0.5)
			(connect_pads
				(clearance 0)
			)
			(min_thickness 0.25)
			(keepout
				(tracks allowed)
				(vias not_allowed)
				(pads allowed)
				(copperpour not_allowed)
				(footprints allowed)
			)
			(placement
				(enabled no)
				(sheetname "")
			)
			(fill
				(thermal_gap 0.5)
				(thermal_bridge_width 0.5)
				(island_removal_mode 0)
			)
			(polygon
				(pts
					(xy 385.5466 -108.74248) (xy 385.9276 -108.74248) (xy 385.9276 -108.56722) (xy 385.5466 -108.566966)
				)
			)
		)
		(zone
			(layer "B.Cu")
			(hatch none 0.5)
			(connect_pads
				(clearance 0)
			)
			(min_thickness 0.25)
			(keepout
				(tracks not_allowed)
				(vias allowed)
				(pads allowed)
				(copperpour not_allowed)
				(footprints allowed)
			)
			(placement
				(enabled no)
				(sheetname "")
			)
			(fill
				(thermal_gap 0.5)
				(thermal_bridge_width 0.5)
				(island_removal_mode 0)
			)
			(polygon
				(pts
					(xy 385.5466 -108.74248) (xy 385.9276 -108.74248) (xy 385.9276 -108.56722) (xy 385.5466 -108.566966)
				)
			)
		)
	)
	(footprint ""
		(layer "B.Cu")
		(at 370.9924 -131.4704 180)
		(property "Reference" "C3M31"
			(at 0 0 0)
			(layer "B.SilkS")
			(hide yes)
			(effects
				(font
					(size 1.27 1.27)
				)
				(justify mirror)
			)
		)
		(property "Value" ""
			(at 0 0 0)
			(layer "B.Fab")
			(effects
				(font
					(size 1.27 1.27)
				)
				(justify mirror)
			)
		)
		(duplicate_pad_numbers_are_jumpers no)
		(fp_rect
			(start 0.3048 -0.1016)
			(end -0.3048 0.9906)
			(stroke
				(width 0)
				(type default)
			)
			(fill no)
			(layer "B.CrtYd")
		)
		(fp_line
			(start 0.3048 0.9906)
			(end -0.3048 0.9906)
			(stroke
				(width 0.1)
				(type default)
			)
			(layer "B.Fab")
		)
		(fp_line
			(start 0.3048 -0.1016)
			(end 0.3048 0.9906)
			(stroke
				(width 0.1)
				(type default)
			)
			(layer "B.Fab")
		)
		(fp_line
			(start -0.3048 0.9906)
			(end -0.3048 -0.1016)
			(stroke
				(width 0.1)
				(type default)
			)
			(layer "B.Fab")
		)
		(fp_line
			(start -0.3048 -0.1016)
			(end 0.3048 -0.1016)
			(stroke
				(width 0.1)
				(type default)
			)
			(layer "B.Fab")
		)
		(pad "1" smd rect
			(at 0 0)
			(size 0.508 0.508)
			(layers "B.Cu" "B.Mask" "B.Paste")
			(net "P1V05_PCH_STBY")
		)
		(pad "2" smd rect
			(at 0 0.889)
			(size 0.508 0.508)
			(layers "B.Cu" "B.Mask" "B.Paste")
			(net "GND")
		)
		(zone
			(layer "B.Cu")
			(hatch none 0.5)
			(connect_pads
				(clearance 0)
			)
			(min_thickness 0.25)
			(keepout
				(tracks not_allowed)
				(vias allowed)
				(pads allowed)
				(copperpour not_allowed)
				(footprints allowed)
			)
			(placement
				(enabled no)
				(sheetname "")
			)
			(fill
				(thermal_gap 0.5)
				(thermal_bridge_width 0.5)
				(island_removal_mode 0)
			)
			(polygon
				(pts
					(xy 370.7384 -131.7244) (xy 371.2464 -131.7244) (xy 371.2464 -132.1054) (xy 370.7384 -132.1054)
				)
			)
		)
		(zone
			(layer "B.Cu")
			(hatch none 0.5)
			(connect_pads
				(clearance 0)
			)
			(min_thickness 0.25)
			(keepout
				(tracks allowed)
				(vias not_allowed)
				(pads allowed)
				(copperpour not_allowed)
				(footprints allowed)
			)
			(placement
				(enabled no)
				(sheetname "")
			)
			(fill
				(thermal_gap 0.5)
				(thermal_bridge_width 0.5)
				(island_removal_mode 0)
			)
			(polygon
				(pts
					(xy 370.7384 -131.7244) (xy 371.2464 -131.7244) (xy 371.2464 -132.1054) (xy 370.7384 -132.1054)
				)
			)
		)
	)
)
